#ISCELL
  mstr_symbols intel_corp_bpage *
  *
#ISCELL
  mstr_symbols gnd *
  page255_i10
#CELL
  mstr_discrete cap *
  page255_i11
#CELL
  w_hdl u74ahct1g125g-al5-r-gp-u *
  page255_i111
#CELL
  w_hdl u74ahct1g125g-al5-r-gp-u *
  page255_i112
#ISCELL
  mstr_symbols gnd *
  page255_i113
#ISCELL
  mstr_symbols gnd *
  page255_i114
#ISCELL
  mstr_symbols gnd *
  page255_i115
#ISCELL
  mstr_symbols gnd *
  page255_i116
#ISCELL
  w_power w_vcc_circle *
  page255_i117
#CELL
  dev_discrete cap_a *
  page255_i118
#ISCELL
  mstr_symbols gnd *
  page255_i119
#CELL
  mstr_discrete cap *
  page255_i12
#CELL
  w_hdl rb551v30-gp *
  page255_i128
#CELL
  mstr_discrete diodeac_dual_array *
  page255_i129
#ISCELL
  mstr_standard offpage *
  page255_i13
#ISCELL
  mstr_symbols gnd *
  page255_i130
#CELL
  mstr_discrete diodeac_dual_array *
  page255_i131
#ISCELL
  mstr_symbols gnd *
  page255_i132
#ISCELL
  mstr_symbols gnd *
  page255_i133
#CELL
  dev_discrete cap_a *
  page255_i134
#ISCELL
  w_power w_vcc_circle *
  page255_i135
#CELL
  w_hdl smc-con13-gp *
  page255_i136
#ISCELL
  mstr_symbols gnd *
  page255_i137
#ISCELL
  mstr_symbols gnd *
  page255_i138
#ISCELL
  mstr_symbols gnd *
  page255_i139
#ISCELL
  mstr_standard offpage *
  page255_i14
#ISCELL
  mstr_symbols gnd *
  page255_i140
#ISCELL
  mstr_symbols gnd *
  page255_i141
#ISCELL
  mstr_symbols gnd *
  page255_i142
#ISCELL
  mstr_symbols gnd *
  page255_i144
#ISCELL
  mstr_symbols p5v *
  page255_i145
#ISCELL
  mstr_standard offpage *
  page255_i15
#CELL
  mstr_discrete cap *
  page255_i16
#ISCELL
  mstr_symbols gnd *
  page255_i17
#CELL
  mstr_discrete cap *
  page255_i18
#ISCELL
  mstr_symbols gnd *
  page255_i19
#ISCELL
  mstr_symbols gnd *
  page255_i20
#CELL
  mstr_discrete cap *
  page255_i21
#CELL
  mstr_discrete res *
  page255_i22
#ISCELL
  mstr_symbols gnd *
  page255_i23
#CELL
  mstr_discrete res *
  page255_i24
#ISCELL
  mstr_symbols gnd *
  page255_i25
#CELL
  mstr_discrete res *
  page255_i26
#ISCELL
  mstr_symbols gnd *
  page255_i27
#ISCELL
  mstr_symbols p3v3 *
  page255_i29
#CELL
  mstr_discrete res *
  page255_i30
#CELL
  mstr_discrete res *
  page255_i31
#ISCELL
  w_power w_vcc_circle *
  page255_i32
#ISCELL
  mstr_standard offpage *
  page255_i33
#CELL
  mstr_discrete res *
  page255_i34
#CELL
  mstr_discrete cap *
  page255_i35
#ISCELL
  mstr_symbols gnd *
  page255_i36
#CELL
  mstr_discrete res *
  page255_i38
#CELL
  mstr_discrete cap *
  page255_i39
#ISCELL
  mstr_symbols gnd *
  page255_i40
#ISCELL
  w_power w_vcc_circle *
  page255_i41
#ISCELL
  mstr_symbols p3v3 *
  page255_i42
#CELL
  mstr_discrete res *
  page255_i43
#CELL
  mstr_discrete res *
  page255_i44
#ISCELL
  mstr_standard offpage *
  page255_i46
#CELL
  mstr_discrete res *
  page255_i49
#ISCELL
  mstr_standard offpage *
  page255_i54
#ISCELL
  mstr_standard offpage *
  page255_i55
#CELL
  mstr_discrete res *
  page255_i59
#CELL
  mstr_discrete cap *
  page255_i60
#ISCELL
  mstr_symbols gnd *
  page255_i61
#CELL
  mstr_discrete cap *
  page255_i62
#ISCELL
  mstr_symbols gnd *
  page255_i63
#CELL
  mstr_discrete cap *
  page255_i7
#ISCELL
  w_power w_vcc_circle *
  page255_i72
#CELL
  dev_discrete cap_a *
  page255_i74
#ISCELL
  mstr_symbols gnd *
  page255_i75
#CELL
  w_hdl ind-68nh-15-gp *
  page255_i76
#CELL
  w_hdl ind-68nh-15-gp *
  page255_i77
#CELL
  w_hdl ind-68nh-15-gp *
  page255_i78
#ISCELL
  mstr_symbols gnd *
  page255_i8
#CELL
  w_hdl polysw-d5a6v-2-gp-u *
  page255_i89
#ISCELL
  mstr_symbols gnd *
  page255_i9
#ISCELL
  w_power w_vcc_circle *
  page255_i91
#CELL
  mstr_discrete fet_n_dual *
  page255_i95
#CELL
  mstr_discrete fet_n_dual *
  page255_i96
